# BASEBOARD_FAB2 (Tioga Pass) — schematic netlist excerpt (pin names and nets, part order shuffled) for the footprints in the layout excerpt that follows; sources: Cadence DE-HDL packaged netlist, KiCad conversion of Wiwynn_Tioga_Pass_MB.brd

J7G3  CONN12_C73564003  CONN  pkg PIP  page 136
  IO1  = TP_ME_RCVR_BOOT
  IO2  = TP_BIOS_USB_RECOVERY
  IO3  = FM_ME_RECOVER_N
  IO4  = FM_BIOS_USB_RECOVERY
  IO5  = PD_ME_RCVR_N
  IO6  = PU_BIOS_USB_RECOVERY
  IO7  = TP_PASSWORD_CLEAR
  IO8  = TP_BIOS_RECOVER_BOOT
  IO9  = FM_PASSWORD_CLEAR_N
  IO10  = FM_BIOS_TOP_SWAP
  IO11  = PD_PASSWORD_CLEAR
  IO12  = PU_BIOS_RECOVER_BOOT

(kicad_pcb
	(version 20260206)
	(generator "pcbnew")
	(generator_version "10.0")
	(general
		(thickness 1.6)
		(legacy_teardrops no)
	)
	(paper "A4")
	(title_block
		(title "Wiwynn_Tioga_Pass_MB.brd")
		(comment 1 "Tioga Pass / footprint 1343 of 4770 (J7G3), pads 1-12 of 12")
	)
	(layers
		(0 "F.Cu" signal "TOP")
		(4 "In1.Cu" signal "L2GND")
		(6 "In2.Cu" signal "L3")
		(8 "In3.Cu" signal "L4GND")
		(10 "In4.Cu" signal "L5")
		(12 "In5.Cu" signal "L6GND")
		(14 "In6.Cu" signal "L7VCC")
		(16 "In7.Cu" signal "L8VCC")
		(18 "In8.Cu" signal "L9GND")
		(20 "In9.Cu" signal "L10")
		(22 "In10.Cu" signal "L11GND")
		(24 "In11.Cu" signal "L12")
		(26 "In12.Cu" signal "L13GND")
		(2 "B.Cu" signal "BOTTOM")
		(9 "F.Adhes" user "F.Adhesive")
		(11 "B.Adhes" user "B.Adhesive")
		(13 "F.Paste" user "Package Geometry/Pastemask Top")
		(15 "B.Paste" user "Package Geometry/Pastemask Bottom")
		(5 "F.SilkS" user "Ref Des/Silkscreen Top")
		(7 "B.SilkS" user "Ref Des/Silkscreen Bottom")
		(1 "F.Mask" user "Board Geometry/Soldermask Top")
		(3 "B.Mask" user "Board Geometry/Soldermask Bottom")
		(17 "Dwgs.User" user "User.Drawings")
		(19 "Cmts.User" user "User.Comments")
		(21 "Eco1.User" user "User.Eco1")
		(23 "Eco2.User" user "User.Eco2")
		(25 "Edge.Cuts" user "Board Geometry/Outline")
		(27 "Margin" user)
		(31 "F.CrtYd" user "Package Geometry/Place Bound Top")
		(29 "B.CrtYd" user "Package Geometry/Place Bound Bottom")
		(35 "F.Fab" user "Ref Des/Assembly Top")
		(33 "B.Fab" user "Ref Des/Assembly Bottom")
	)
	(footprint ""
		(layer "F.Cu")
		(at 366.268 3.81 90)
		(property "Reference" "J7G3"
			(at 5.63245 2.22758 0)
			(unlocked yes)
			(layer "F.SilkS")
			(effects
				(font
					(size 0.7874 0.5842)
					(thickness 0.1524)
				)
			)
		)
		(property "Value" ""
			(at 0 0 90)
			(layer "F.Fab")
			(effects
				(font
					(size 1.27 1.27)
				)
			)
		)
		(duplicate_pad_numbers_are_jumpers no)
		(pad "1" thru_hole rect
			(at 0 0 90)
			(size 1.6256 1.6256)
			(drill 1.2446)
			(layers "*.Cu" "*.Mask")
			(remove_unused_layers no)
			(net "TP_ME_RCVR_BOOT")
			(clearance 0.127)
			(thermal_gap 0.127)
			(padstack
				(mode front_inner_back)
				(layer "Inner"
					(shape circle)
					(size 1.6256 1.6256)
					(clearance 0.127)
				)
				(layer "B.Cu"
					(shape rect)
					(size 1.6256 1.6256)
					(clearance 0.127)
				)
			)
		)
		(pad "2" thru_hole circle
			(at 2.54 0 90)
			(size 1.6256 1.6256)
			(drill 1.2446)
			(layers "*.Cu" "*.Mask")
			(remove_unused_layers no)
			(net "TP_BIOS_USB_RECOVERY")
			(clearance 0.127)
			(thermal_gap 0.127)
		)
		(pad "3" thru_hole circle
			(at 0 2.54 90)
			(size 1.6256 1.6256)
			(drill 1.2446)
			(layers "*.Cu" "*.Mask")
			(remove_unused_layers no)
			(net "FM_ME_RECOVER_N")
			(clearance 0.127)
			(thermal_gap 0.127)
		)
		(pad "4" thru_hole circle
			(at 2.54 2.54 90)
			(size 1.6256 1.6256)
			(drill 1.2446)
			(layers "*.Cu" "*.Mask")
			(remove_unused_layers no)
			(net "FM_BIOS_USB_RECOVERY")
			(clearance 0.127)
			(thermal_gap 0.127)
		)
		(pad "5" thru_hole circle
			(at 0 5.08 90)
			(size 1.6256 1.6256)
			(drill 1.2446)
			(layers "*.Cu" "*.Mask")
			(remove_unused_layers no)
			(net "PD_ME_RCVR_N")
			(clearance 0.127)
			(thermal_gap 0.127)
		)
		(pad "6" thru_hole circle
			(at 2.54 5.08 90)
			(size 1.6256 1.6256)
			(drill 1.2446)
			(layers "*.Cu" "*.Mask")
			(remove_unused_layers no)
			(net "PU_BIOS_USB_RECOVERY")
			(clearance 0.127)
			(thermal_gap 0.127)
		)
		(pad "7" thru_hole circle
			(at 0 7.62 90)
			(size 1.6256 1.6256)
			(drill 1.2446)
			(layers "*.Cu" "*.Mask")
			(remove_unused_layers no)
			(net "TP_PASSWORD_CLEAR")
			(clearance 0.127)
			(thermal_gap 0.127)
		)
		(pad "8" thru_hole circle
			(at 2.54 7.62 90)
			(size 1.6256 1.6256)
			(drill 1.2446)
			(layers "*.Cu" "*.Mask")
			(remove_unused_layers no)
			(net "TP_BIOS_RECOVER_BOOT")
			(clearance 0.127)
			(thermal_gap 0.127)
		)
		(pad "9" thru_hole circle
			(at 0 10.16 90)
			(size 1.6256 1.6256)
			(drill 1.2446)
			(layers "*.Cu" "*.Mask")
			(remove_unused_layers no)
			(net "FM_PASSWORD_CLEAR_N")
			(clearance 0.127)
			(thermal_gap 0.127)
		)
		(pad "10" thru_hole circle
			(at 2.54 10.16 90)
			(size 1.6256 1.6256)
			(drill 1.2446)
			(layers "*.Cu" "*.Mask")
			(remove_unused_layers no)
			(net "FM_BIOS_TOP_SWAP")
			(clearance 0.127)
			(thermal_gap 0.127)
		)
		(pad "11" thru_hole circle
			(at 0 12.7 90)
			(size 1.6256 1.6256)
			(drill 1.2446)
			(layers "*.Cu" "*.Mask")
			(remove_unused_layers no)
			(net "PD_PASSWORD_CLEAR")
			(clearance 0.127)
			(thermal_gap 0.127)
		)
		(pad "12" thru_hole circle
			(at 2.54 12.7 90)
			(size 1.6256 1.6256)
			(drill 1.2446)
			(layers "*.Cu" "*.Mask")
			(remove_unused_layers no)
			(net "PU_BIOS_RECOVER_BOOT")
			(clearance 0.127)
			(thermal_gap 0.127)
		)
	)
)
